(kicad_pcb
	(version 20260206)
	(generator "pcbnew")
	(generator_version "10.0")
	(general
		(thickness 1.6)
		(legacy_teardrops no)
	)
	(paper "A4")
	(title_block
		(title "v1-tray-backplane — T6M_tray_BP_c_1023_1120.brd")
		(comment 1 "Open CloudServer (Microsoft) / footprint 46 of 170 (U9), pads 1-12 of 12")
	)
	(layers
		(0 "F.Cu" signal "TOP")
		(4 "In1.Cu" signal "GND")
		(6 "In2.Cu" signal "IN1")
		(8 "In3.Cu" signal "VCC")
		(10 "In4.Cu" signal "VCC1")
		(12 "In5.Cu" signal "IN2")
		(14 "In6.Cu" signal "GND1")
		(2 "B.Cu" signal "BOTTOM")
		(9 "F.Adhes" user "F.Adhesive")
		(11 "B.Adhes" user "B.Adhesive")
		(13 "F.Paste" user "Package Geometry/Pastemask Top")
		(15 "B.Paste" user "Package Geometry/Pastemask Bottom")
		(5 "F.SilkS" user "Ref Des/Silkscreen Top")
		(7 "B.SilkS" user "Ref Des/Silkscreen Bottom")
		(1 "F.Mask" user "Board Geometry/Soldermask Top")
		(3 "B.Mask" user "Board Geometry/Soldermask Bottom")
		(17 "Dwgs.User" user "User.Drawings")
		(19 "Cmts.User" user "User.Comments")
		(21 "Eco1.User" user "User.Eco1")
		(23 "Eco2.User" user "User.Eco2")
		(25 "Edge.Cuts" user "Board Geometry/Outline")
		(27 "Margin" user)
		(31 "F.CrtYd" user "Package Geometry/Place Bound Top")
		(29 "B.CrtYd" user "Package Geometry/Place Bound Bottom")
		(35 "F.Fab" user "Ref Des/Assembly Top")
		(33 "B.Fab" user "Ref Des/Assembly Bottom")
	)
	(footprint ""
		(layer "F.Cu")
		(at 402.988018 -33.589976)
		(property "Reference" "U9"
			(at -21.532342 -12.261342 90)
			(unlocked yes)
			(layer "F.SilkS")
			(effects
				(font
					(size 0.7874 0.5842)
					(thickness 0.1524)
				)
				(justify left)
			)
		)
		(property "Value" ""
			(at 0 0 0)
			(layer "F.Fab")
			(effects
				(font
					(size 1.27 1.27)
				)
			)
		)
		(duplicate_pad_numbers_are_jumpers no)
		(pad "A1" smd rect
			(at 12.109958 12.62507)
			(size 0.9144 2.1336)
			(layers "F.Cu" "F.Mask" "F.Paste")
			(net "GND")
		)
		(pad "A2" smd rect
			(at 9.709912 12.62507)
			(size 0.9144 2.1336)
			(layers "F.Cu" "F.Mask" "F.Paste")
			(net "GND")
		)
		(pad "A3" smd rect
			(at 7.31012 12.62507)
			(size 0.9144 2.1336)
			(layers "F.Cu" "F.Mask" "F.Paste")
			(net "GND")
		)
		(pad "B1" smd rect
			(at -6.89991 12.62507)
			(size 0.9144 2.1336)
			(layers "F.Cu" "F.Mask" "F.Paste")
			(net "GND")
		)
		(pad "B2" smd rect
			(at -9.299956 12.62507)
			(size 0.9144 2.1336)
			(layers "F.Cu" "F.Mask" "F.Paste")
			(net "GND")
		)
		(pad "B3" smd rect
			(at -11.700002 12.62507)
			(size 0.9144 2.1336)
			(layers "F.Cu" "F.Mask" "F.Paste")
			(net "GND")
		)
		(pad "G1" thru_hole circle
			(at -19.61007 -8.999982)
			(size 3.5306 3.5306)
			(drill 2.5146)
			(layers "*.Cu" "*.Mask")
			(remove_unused_layers no)
			(net "GND")
			(clearance -0.254)
		)
		(pad "G2" thru_hole circle
			(at -19.120104 0)
			(size 2.3368 2.3368)
			(drill 1.5748)
			(layers "*.Cu" "*.Mask")
			(remove_unused_layers no)
			(net "GND")
			(clearance -0.127)
		)
		(pad "G3" thru_hole circle
			(at -19.61007 5.999988)
			(size 3.5306 3.5306)
			(drill 2.5146)
			(layers "*.Cu" "*.Mask")
			(remove_unused_layers no)
			(net "GND")
			(clearance -0.254)
		)
		(pad "G4" thru_hole circle
			(at 19.61007 -8.999982)
			(size 3.5306 3.5306)
			(drill 2.5146)
			(layers "*.Cu" "*.Mask")
			(remove_unused_layers no)
			(net "GND")
			(clearance -0.254)
		)
		(pad "G5" thru_hole circle
			(at 19.120104 0)
			(size 2.3368 2.3368)
			(drill 1.5748)
			(layers "*.Cu" "*.Mask")
			(remove_unused_layers no)
			(net "GND")
			(clearance -0.127)
		)
		(pad "G6" thru_hole circle
			(at 19.61007 5.999988)
			(size 3.5306 3.5306)
			(drill 2.5146)
			(layers "*.Cu" "*.Mask")
			(remove_unused_layers no)
			(net "GND")
			(clearance -0.254)
		)
	)
)
